(kicad_pcb
	(version 20260206)
	(generator "pcbnew")
	(generator_version "10.0")
	(general
		(thickness 1.6)
		(legacy_teardrops no)
	)
	(paper "A4")
	(title_block
		(title "03242023_DA0F0TMBIJ0_F0T_Motherboard_J_brd_V01_OCP.brd")
		(comment 1 "Grand Teton / footprints 4124-4128 of 6105")
	)
	(layers
		(0 "F.Cu" signal "TOP")
		(4 "In1.Cu" signal "GND")
		(6 "In2.Cu" signal "IN1")
		(8 "In3.Cu" signal "GND1")
		(10 "In4.Cu" signal "IN2")
		(12 "In5.Cu" signal "GND2")
		(14 "In6.Cu" signal "IN3")
		(16 "In7.Cu" signal "GND3")
		(18 "In8.Cu" signal "VCC")
		(20 "In9.Cu" signal "VCC1")
		(22 "In10.Cu" signal "GND4")
		(24 "In11.Cu" signal "IN4")
		(26 "In12.Cu" signal "GND5")
		(28 "In13.Cu" signal "IN5")
		(30 "In14.Cu" signal "GND6")
		(32 "In15.Cu" signal "IN6")
		(34 "In16.Cu" signal "GND7")
		(2 "B.Cu" signal "BOTTOM")
		(9 "F.Adhes" user "F.Adhesive")
		(11 "B.Adhes" user "B.Adhesive")
		(13 "F.Paste" user "Package Geometry/Pastemask Top")
		(15 "B.Paste" user "Package Geometry/Pastemask Bottom")
		(5 "F.SilkS" user "Ref Des/Silkscreen Top")
		(7 "B.SilkS" user "Ref Des/Silkscreen Bottom")
		(1 "F.Mask" user "Board Geometry/Soldermask Top")
		(3 "B.Mask" user "Board Geometry/Soldermask Bottom")
		(17 "Dwgs.User" user "User.Drawings")
		(19 "Cmts.User" user "User.Comments")
		(21 "Eco1.User" user "User.Eco1")
		(23 "Eco2.User" user "User.Eco2")
		(25 "Edge.Cuts" user "Board Geometry/Outline")
		(27 "Margin" user)
		(31 "F.CrtYd" user "Package Geometry/Place Bound Top")
		(29 "B.CrtYd" user "Package Geometry/Place Bound Bottom")
		(35 "F.Fab" user "Ref Des/Assembly Top")
		(33 "B.Fab" user "Ref Des/Assembly Bottom")
	)
	(footprint ""
		(layer "F.Cu")
		(at 61.26988 -16.220948 -90)
		(property "Reference" "R3171"
			(at 0 0 270)
			(layer "F.SilkS")
			(hide yes)
			(effects
				(font
					(size 1.27 1.27)
				)
			)
		)
		(property "Value" ""
			(at 0 0 270)
			(layer "F.Fab")
			(effects
				(font
					(size 1.27 1.27)
				)
			)
		)
		(duplicate_pad_numbers_are_jumpers no)
		(fp_line
			(start -0.7874 0.4064)
			(end -0.7874 -0.4064)
			(stroke
				(width 0.1524)
				(type default)
			)
			(layer "F.SilkS")
		)
		(fp_line
			(start 0.7874 0.4064)
			(end -0.7874 0.4064)
			(stroke
				(width 0.1524)
				(type default)
			)
			(layer "F.SilkS")
		)
		(fp_line
			(start -0.7874 -0.4064)
			(end 0.7874 -0.4064)
			(stroke
				(width 0.1524)
				(type default)
			)
			(layer "F.SilkS")
		)
		(fp_line
			(start 0.7874 -0.4064)
			(end 0.7874 0.4064)
			(stroke
				(width 0.1524)
				(type default)
			)
			(layer "F.SilkS")
		)
		(fp_line
			(start -0.67945 0.3048)
			(end -0.67945 -0.305054)
			(stroke
				(width 0.1)
				(type default)
			)
			(layer "F.Fab")
		)
		(fp_line
			(start -0.12065 0.3048)
			(end -0.67945 0.3048)
			(stroke
				(width 0.1)
				(type default)
			)
			(layer "F.Fab")
		)
		(fp_line
			(start 0.120396 0.3048)
			(end 0.120396 0.2794)
			(stroke
				(width 0.1)
				(type default)
			)
			(layer "F.Fab")
		)
		(fp_line
			(start 0.67945 0.3048)
			(end 0.120396 0.3048)
			(stroke
				(width 0.1)
				(type default)
			)
			(layer "F.Fab")
		)
		(fp_line
			(start -0.12065 0.2794)
			(end -0.12065 0.3048)
			(stroke
				(width 0.1)
				(type default)
			)
			(layer "F.Fab")
		)
		(fp_line
			(start 0.120396 0.2794)
			(end -0.12065 0.2794)
			(stroke
				(width 0.1)
				(type default)
			)
			(layer "F.Fab")
		)
		(fp_line
			(start -0.12065 -0.2794)
			(end 0.12065 -0.2794)
			(stroke
				(width 0.1)
				(type default)
			)
			(layer "F.Fab")
		)
		(fp_line
			(start 0.12065 -0.2794)
			(end 0.12065 -0.3048)
			(stroke
				(width 0.1)
				(type default)
			)
			(layer "F.Fab")
		)
		(fp_line
			(start 0.12065 -0.3048)
			(end 0.67945 -0.3048)
			(stroke
				(width 0.1)
				(type default)
			)
			(layer "F.Fab")
		)
		(fp_line
			(start 0.67945 -0.3048)
			(end 0.67945 0.3048)
			(stroke
				(width 0.1)
				(type default)
			)
			(layer "F.Fab")
		)
		(fp_line
			(start -0.67945 -0.305054)
			(end -0.12065 -0.305054)
			(stroke
				(width 0.1)
				(type default)
			)
			(layer "F.Fab")
		)
		(fp_line
			(start -0.12065 -0.305054)
			(end -0.12065 -0.2794)
			(stroke
				(width 0.1)
				(type default)
			)
			(layer "F.Fab")
		)
		(pad "1" smd circle
			(at -0.40005 0 270)
			(size 0 0)
			(layers "F.Cu" "F.Mask" "F.Paste")
			(net "OCP_V3_2_ISO_BIF2_EN")
		)
		(pad "2" smd circle
			(at 0.40005 0 270)
			(size 0 0)
			(layers "F.Cu" "F.Mask" "F.Paste")
			(net "OCP_V3_2_BIF2_R_N")
		)
	)
	(footprint ""
		(layer "F.Cu")
		(at 77.55001 -24.713946 -90)
		(property "Reference" "PR3830"
			(at 0 0 270)
			(layer "F.SilkS")
			(hide yes)
			(effects
				(font
					(size 1.27 1.27)
				)
			)
		)
		(property "Value" ""
			(at 0 0 270)
			(layer "F.Fab")
			(effects
				(font
					(size 1.27 1.27)
				)
			)
		)
		(duplicate_pad_numbers_are_jumpers no)
		(fp_line
			(start -0.7874 0.4064)
			(end -0.7874 -0.4064)
			(stroke
				(width 0.1524)
				(type default)
			)
			(layer "F.SilkS")
		)
		(fp_line
			(start 0.7874 0.4064)
			(end -0.7874 0.4064)
			(stroke
				(width 0.1524)
				(type default)
			)
			(layer "F.SilkS")
		)
		(fp_line
			(start -0.7874 -0.4064)
			(end 0.7874 -0.4064)
			(stroke
				(width 0.1524)
				(type default)
			)
			(layer "F.SilkS")
		)
		(fp_line
			(start 0.7874 -0.4064)
			(end 0.7874 0.4064)
			(stroke
				(width 0.1524)
				(type default)
			)
			(layer "F.SilkS")
		)
		(fp_line
			(start -0.67945 0.3048)
			(end -0.67945 -0.305054)
			(stroke
				(width 0.1)
				(type default)
			)
			(layer "F.Fab")
		)
		(fp_line
			(start -0.12065 0.3048)
			(end -0.67945 0.3048)
			(stroke
				(width 0.1)
				(type default)
			)
			(layer "F.Fab")
		)
		(fp_line
			(start 0.120396 0.3048)
			(end 0.120396 0.2794)
			(stroke
				(width 0.1)
				(type default)
			)
			(layer "F.Fab")
		)
		(fp_line
			(start 0.67945 0.3048)
			(end 0.120396 0.3048)
			(stroke
				(width 0.1)
				(type default)
			)
			(layer "F.Fab")
		)
		(fp_line
			(start -0.12065 0.2794)
			(end -0.12065 0.3048)
			(stroke
				(width 0.1)
				(type default)
			)
			(layer "F.Fab")
		)
		(fp_line
			(start 0.120396 0.2794)
			(end -0.12065 0.2794)
			(stroke
				(width 0.1)
				(type default)
			)
			(layer "F.Fab")
		)
		(fp_line
			(start -0.12065 -0.2794)
			(end 0.12065 -0.2794)
			(stroke
				(width 0.1)
				(type default)
			)
			(layer "F.Fab")
		)
		(fp_line
			(start 0.12065 -0.2794)
			(end 0.12065 -0.3048)
			(stroke
				(width 0.1)
				(type default)
			)
			(layer "F.Fab")
		)
		(fp_line
			(start 0.12065 -0.3048)
			(end 0.67945 -0.3048)
			(stroke
				(width 0.1)
				(type default)
			)
			(layer "F.Fab")
		)
		(fp_line
			(start 0.67945 -0.3048)
			(end 0.67945 0.3048)
			(stroke
				(width 0.1)
				(type default)
			)
			(layer "F.Fab")
		)
		(fp_line
			(start -0.67945 -0.305054)
			(end -0.12065 -0.305054)
			(stroke
				(width 0.1)
				(type default)
			)
			(layer "F.Fab")
		)
		(fp_line
			(start -0.12065 -0.305054)
			(end -0.12065 -0.2794)
			(stroke
				(width 0.1)
				(type default)
			)
			(layer "F.Fab")
		)
		(pad "1" smd circle
			(at -0.40005 0 270)
			(size 0 0)
			(layers "F.Cu" "F.Mask" "F.Paste")
			(net "P12V_AUX")
		)
		(pad "2" smd circle
			(at 0.40005 0 270)
			(size 0 0)
			(layers "F.Cu" "F.Mask" "F.Paste")
			(net "P12V_OCP_VCC_2")
		)
	)
	(footprint ""
		(layer "F.Cu")
		(at 260.731508 -4.696206)
		(property "Reference" "J75"
			(at -4.164838 1.013206 90)
			(unlocked yes)
			(layer "F.SilkS")
			(effects
				(font
					(size 0.7874 0.5842)
					(thickness 0.1524)
				)
				(justify left)
			)
		)
		(property "Value" ""
			(at 0 0 0)
			(layer "F.Fab")
			(effects
				(font
					(size 1.27 1.27)
				)
			)
		)
		(duplicate_pad_numbers_are_jumpers no)
		(fp_line
			(start -1.2192 -2.1082)
			(end 1.2192 -2.1082)
			(stroke
				(width 0.1524)
				(type default)
			)
			(layer "F.SilkS")
		)
		(fp_line
			(start -1.2192 2.1082)
			(end -1.2192 -2.1082)
			(stroke
				(width 0.1524)
				(type default)
			)
			(layer "F.SilkS")
		)
		(fp_line
			(start 1.2192 -2.1082)
			(end 1.2192 2.1082)
			(stroke
				(width 0.1524)
				(type default)
			)
			(layer "F.SilkS")
		)
		(fp_line
			(start 1.2192 2.1082)
			(end -1.2192 2.1082)
			(stroke
				(width 0.1524)
				(type default)
			)
			(layer "F.SilkS")
		)
		(pad "" np_thru_hole circle
			(at -2.8829 -1.27 270)
			(size 1.0414 1.0414)
			(drill 1.0414)
			(layers "*.Cu" "*.Mask")
			(clearance 0.381)
			(thermal_gap 0.381)
		)
		(pad "" np_thru_hole circle
			(at -2.8829 1.27 270)
			(size 1.0414 1.0414)
			(drill 1.0414)
			(layers "*.Cu" "*.Mask")
			(clearance 0.381)
			(thermal_gap 0.381)
		)
		(pad "" np_thru_hole circle
			(at 3.4671 -1.27 270)
			(size 1.0414 1.0414)
			(drill 1.0414)
			(layers "*.Cu" "*.Mask")
			(clearance 0.381)
			(thermal_gap 0.381)
		)
		(pad "" np_thru_hole circle
			(at 3.4671 1.27 270)
			(size 1.0414 1.0414)
			(drill 1.0414)
			(layers "*.Cu" "*.Mask")
			(clearance 0.381)
			(thermal_gap 0.381)
		)
		(pad "1" smd rect
			(at 0.8255 -0.249936 270)
			(size 0.3048 0.508)
			(layers "F.Cu" "F.Mask" "F.Paste")
			(net "DELTA_L_85_10INCH_TOP_DP")
		)
		(pad "2" smd rect
			(at 0.8255 0.249936 270)
			(size 0.3048 0.508)
			(layers "F.Cu" "F.Mask" "F.Paste")
			(net "DELTA_L_85_10INCH_TOP_DN")
		)
		(pad "3" smd circle
			(at 0 0)
			(size 0 0)
			(layers "F.Cu" "F.Mask" "F.Paste")
			(net "DELTA_L_GND_1")
		)
		(zone
			(layer "F.Cu")
			(hatch none 0.5)
			(connect_pads
				(clearance 0)
			)
			(min_thickness 0.25)
			(keepout
				(tracks not_allowed)
				(vias allowed)
				(pads allowed)
				(copperpour not_allowed)
				(footprints allowed)
			)
			(placement
				(enabled no)
				(sheetname "")
			)
			(fill
				(thermal_gap 0.5)
				(thermal_bridge_width 0.5)
				(island_removal_mode 0)
			)
			(polygon
				(pts
					(xy 261.849108 -5.244846) (xy 261.849108 -5.149342) (xy 261.252208 -5.149342) (xy 261.252208 -4.742942)
					(xy 261.849108 -4.742942) (xy 261.849108 -4.64947) (xy 261.252208 -4.64947) (xy 261.252208 -4.24307)
					(xy 261.849108 -4.24307) (xy 261.849108 -4.147566) (xy 261.150608 -4.147566) (xy 261.150608 -5.244846)
				)
			)
		)
		(zone
			(layers "F.Cu" "B.Cu" "In1.Cu" "In2.Cu" "In3.Cu" "In4.Cu" "In5.Cu" "In6.Cu"
				"In7.Cu" "In8.Cu" "In9.Cu" "In10.Cu" "In11.Cu" "In12.Cu" "In13.Cu" "In14.Cu"
				"In15.Cu" "In16.Cu"
			)
			(hatch none 0.5)
			(connect_pads
				(clearance 0)
			)
			(min_thickness 0.25)
			(keepout
				(tracks not_allowed)
				(vias allowed)
				(pads allowed)
				(copperpour not_allowed)
				(footprints allowed)
			)
			(placement
				(enabled no)
				(sheetname "")
			)
			(fill
				(thermal_gap 0.5)
				(thermal_bridge_width 0.5)
				(island_removal_mode 0)
			)
			(polygon
				(pts
					(arc
						(start 258.775708 -5.966206)
						(mid 256.921508 -5.966206)
						(end 258.775708 -5.966206)
					)
				)
			)
		)
		(zone
			(layers "F.Cu" "B.Cu" "In1.Cu" "In2.Cu" "In3.Cu" "In4.Cu" "In5.Cu" "In6.Cu"
				"In7.Cu" "In8.Cu" "In9.Cu" "In10.Cu" "In11.Cu" "In12.Cu" "In13.Cu" "In14.Cu"
				"In15.Cu" "In16.Cu"
			)
			(hatch none 0.5)
			(connect_pads
				(clearance 0)
			)
			(min_thickness 0.25)
			(keepout
				(tracks not_allowed)
				(vias allowed)
				(pads allowed)
				(copperpour not_allowed)
				(footprints allowed)
			)
			(placement
				(enabled no)
				(sheetname "")
			)
			(fill
				(thermal_gap 0.5)
				(thermal_bridge_width 0.5)
				(island_removal_mode 0)
			)
			(polygon
				(pts
					(arc
						(start 258.775708 -3.426206)
						(mid 256.921508 -3.426206)
						(end 258.775708 -3.426206)
					)
				)
			)
		)
		(zone
			(layers "F.Cu" "B.Cu" "In1.Cu" "In2.Cu" "In3.Cu" "In4.Cu" "In5.Cu" "In6.Cu"
				"In7.Cu" "In8.Cu" "In9.Cu" "In10.Cu" "In11.Cu" "In12.Cu" "In13.Cu" "In14.Cu"
				"In15.Cu" "In16.Cu"
			)
			(hatch none 0.5)
			(connect_pads
				(clearance 0)
			)
			(min_thickness 0.25)
			(keepout
				(tracks not_allowed)
				(vias allowed)
				(pads allowed)
				(copperpour not_allowed)
				(footprints allowed)
			)
			(placement
				(enabled no)
				(sheetname "")
			)
			(fill
				(thermal_gap 0.5)
				(thermal_bridge_width 0.5)
				(island_removal_mode 0)
			)
			(polygon
				(pts
					(arc
						(start 265.125708 -5.966206)
						(mid 263.271508 -5.966206)
						(end 265.125708 -5.966206)
					)
				)
			)
		)
		(zone
			(layers "F.Cu" "B.Cu" "In1.Cu" "In2.Cu" "In3.Cu" "In4.Cu" "In5.Cu" "In6.Cu"
				"In7.Cu" "In8.Cu" "In9.Cu" "In10.Cu" "In11.Cu" "In12.Cu" "In13.Cu" "In14.Cu"
				"In15.Cu" "In16.Cu"
			)
			(hatch none 0.5)
			(connect_pads
				(clearance 0)
			)
			(min_thickness 0.25)
			(keepout
				(tracks not_allowed)
				(vias allowed)
				(pads allowed)
				(copperpour not_allowed)
				(footprints allowed)
			)
			(placement
				(enabled no)
				(sheetname "")
			)
			(fill
				(thermal_gap 0.5)
				(thermal_bridge_width 0.5)
				(island_removal_mode 0)
			)
			(polygon
				(pts
					(arc
						(start 265.125708 -3.426206)
						(mid 263.271508 -3.426206)
						(end 265.125708 -3.426206)
					)
				)
			)
		)
	)
	(footprint ""
		(layer "F.Cu")
		(at 282.452826 -19.699986 180)
		(property "Reference" "R3182"
			(at 0 0 180)
			(layer "F.SilkS")
			(hide yes)
			(effects
				(font
					(size 1.27 1.27)
				)
			)
		)
		(property "Value" ""
			(at 0 0 180)
			(layer "F.Fab")
			(effects
				(font
					(size 1.27 1.27)
				)
			)
		)
		(duplicate_pad_numbers_are_jumpers no)
		(fp_line
			(start 0.7874 0.4064)
			(end -0.7874 0.4064)
			(stroke
				(width 0.1524)
				(type default)
			)
			(layer "F.SilkS")
		)
		(fp_line
			(start 0.7874 -0.4064)
			(end 0.7874 0.4064)
			(stroke
				(width 0.1524)
				(type default)
			)
			(layer "F.SilkS")
		)
		(fp_line
			(start -0.7874 0.4064)
			(end -0.7874 -0.4064)
			(stroke
				(width 0.1524)
				(type default)
			)
			(layer "F.SilkS")
		)
		(fp_line
			(start -0.7874 -0.4064)
			(end 0.7874 -0.4064)
			(stroke
				(width 0.1524)
				(type default)
			)
			(layer "F.SilkS")
		)
		(fp_line
			(start 0.67945 0.3048)
			(end 0.120396 0.3048)
			(stroke
				(width 0.1)
				(type default)
			)
			(layer "F.Fab")
		)
		(fp_line
			(start 0.67945 -0.3048)
			(end 0.67945 0.3048)
			(stroke
				(width 0.1)
				(type default)
			)
			(layer "F.Fab")
		)
		(fp_line
			(start 0.12065 -0.2794)
			(end 0.12065 -0.3048)
			(stroke
				(width 0.1)
				(type default)
			)
			(layer "F.Fab")
		)
		(fp_line
			(start 0.12065 -0.3048)
			(end 0.67945 -0.3048)
			(stroke
				(width 0.1)
				(type default)
			)
			(layer "F.Fab")
		)
		(fp_line
			(start 0.120396 0.3048)
			(end 0.120396 0.2794)
			(stroke
				(width 0.1)
				(type default)
			)
			(layer "F.Fab")
		)
		(fp_line
			(start 0.120396 0.2794)
			(end -0.12065 0.2794)
			(stroke
				(width 0.1)
				(type default)
			)
			(layer "F.Fab")
		)
		(fp_line
			(start -0.12065 0.3048)
			(end -0.67945 0.3048)
			(stroke
				(width 0.1)
				(type default)
			)
			(layer "F.Fab")
		)
		(fp_line
			(start -0.12065 0.2794)
			(end -0.12065 0.3048)
			(stroke
				(width 0.1)
				(type default)
			)
			(layer "F.Fab")
		)
		(fp_line
			(start -0.12065 -0.2794)
			(end 0.12065 -0.2794)
			(stroke
				(width 0.1)
				(type default)
			)
			(layer "F.Fab")
		)
		(fp_line
			(start -0.12065 -0.305054)
			(end -0.12065 -0.2794)
			(stroke
				(width 0.1)
				(type default)
			)
			(layer "F.Fab")
		)
		(fp_line
			(start -0.67945 0.3048)
			(end -0.67945 -0.305054)
			(stroke
				(width 0.1)
				(type default)
			)
			(layer "F.Fab")
		)
		(fp_line
			(start -0.67945 -0.305054)
			(end -0.12065 -0.305054)
			(stroke
				(width 0.1)
				(type default)
			)
			(layer "F.Fab")
		)
		(pad "1" smd circle
			(at -0.40005 0 180)
			(size 0 0)
			(layers "F.Cu" "F.Mask" "F.Paste")
			(net "P3V3_OCP_V3_2")
		)
		(pad "2" smd circle
			(at 0.40005 0 180)
			(size 0 0)
			(layers "F.Cu" "F.Mask" "F.Paste")
			(net "IRQ_LVC3_OCP_V3_2_WAKE_N")
		)
	)
	(footprint ""
		(layer "F.Cu")
		(at 193.93408 -355.996748 180)
		(property "Reference" "R1004"
			(at 0 0 180)
			(layer "F.SilkS")
			(hide yes)
			(effects
				(font
					(size 1.27 1.27)
				)
			)
		)
		(property "Value" ""
			(at 0 0 180)
			(layer "F.Fab")
			(effects
				(font
					(size 1.27 1.27)
				)
			)
		)
		(duplicate_pad_numbers_are_jumpers no)
		(fp_line
			(start 0.7874 0.4064)
			(end -0.7874 0.4064)
			(stroke
				(width 0.1524)
				(type default)
			)
			(layer "F.SilkS")
		)
		(fp_line
			(start 0.7874 -0.4064)
			(end 0.7874 0.4064)
			(stroke
				(width 0.1524)
				(type default)
			)
			(layer "F.SilkS")
		)
		(fp_line
			(start -0.7874 0.4064)
			(end -0.7874 -0.4064)
			(stroke
				(width 0.1524)
				(type default)
			)
			(layer "F.SilkS")
		)
		(fp_line
			(start -0.7874 -0.4064)
			(end 0.7874 -0.4064)
			(stroke
				(width 0.1524)
				(type default)
			)
			(layer "F.SilkS")
		)
		(fp_line
			(start 0.67945 0.3048)
			(end 0.120396 0.3048)
			(stroke
				(width 0.1)
				(type default)
			)
			(layer "F.Fab")
		)
		(fp_line
			(start 0.67945 -0.3048)
			(end 0.67945 0.3048)
			(stroke
				(width 0.1)
				(type default)
			)
			(layer "F.Fab")
		)
		(fp_line
			(start 0.12065 -0.2794)
			(end 0.12065 -0.3048)
			(stroke
				(width 0.1)
				(type default)
			)
			(layer "F.Fab")
		)
		(fp_line
			(start 0.12065 -0.3048)
			(end 0.67945 -0.3048)
			(stroke
				(width 0.1)
				(type default)
			)
			(layer "F.Fab")
		)
		(fp_line
			(start 0.120396 0.3048)
			(end 0.120396 0.2794)
			(stroke
				(width 0.1)
				(type default)
			)
			(layer "F.Fab")
		)
		(fp_line
			(start 0.120396 0.2794)
			(end -0.12065 0.2794)
			(stroke
				(width 0.1)
				(type default)
			)
			(layer "F.Fab")
		)
		(fp_line
			(start -0.12065 0.3048)
			(end -0.67945 0.3048)
			(stroke
				(width 0.1)
				(type default)
			)
			(layer "F.Fab")
		)
		(fp_line
			(start -0.12065 0.2794)
			(end -0.12065 0.3048)
			(stroke
				(width 0.1)
				(type default)
			)
			(layer "F.Fab")
		)
		(fp_line
			(start -0.12065 -0.2794)
			(end 0.12065 -0.2794)
			(stroke
				(width 0.1)
				(type default)
			)
			(layer "F.Fab")
		)
		(fp_line
			(start -0.12065 -0.305054)
			(end -0.12065 -0.2794)
			(stroke
				(width 0.1)
				(type default)
			)
			(layer "F.Fab")
		)
		(fp_line
			(start -0.67945 0.3048)
			(end -0.67945 -0.305054)
			(stroke
				(width 0.1)
				(type default)
			)
			(layer "F.Fab")
		)
		(fp_line
			(start -0.67945 -0.305054)
			(end -0.12065 -0.305054)
			(stroke
				(width 0.1)
				(type default)
			)
			(layer "F.Fab")
		)
		(pad "1" smd circle
			(at -0.40005 0 180)
			(size 0 0)
			(layers "F.Cu" "F.Mask" "F.Paste")
			(net "P3V3_AUX")
		)
		(pad "2" smd circle
			(at 0.40005 0 180)
			(size 0 0)
			(layers "F.Cu" "F.Mask" "F.Paste")
			(net "PU_PIROM_CPU1_SM_WP")
		)
	)
)
